# S9S_MB_2U (Grand Teton) — schematic netlist excerpt (pin names and nets, part order shuffled) for the footprints in the layout excerpt that follows; sources: Cadence DE-HDL packaged netlist, KiCad conversion of 03242023_DA0F0TMBIJ0_F0T_Motherboard_J_brd_V01_OCP.brd

C206  Q_CAP  0.1UF 25V 10% X7R  pkg 0402  page 206 : A = P3V3_DB2000_VDD ; B = GND
PC617_P0_1  Q_CAP  22UF 4V 20% X6S  pkg C0805  page 271 : A = PVCCFA_EHV_FIVRA_CPU0 ; B = GND
R423  Q_RES  1K 1% CHIP  pkg 0402LF  page 153 : A = SGPIO_OCP_SFF_CLK ; B = P3V3_OCP_SFF

(kicad_pcb
	(version 20260206)
	(generator "pcbnew")
	(generator_version "10.0")
	(general
		(thickness 1.6)
		(legacy_teardrops no)
	)
	(paper "A4")
	(title_block
		(title "03242023_DA0F0TMBIJ0_F0T_Motherboard_J_brd_V01_OCP.brd")
		(comment 1 "Grand Teton / footprints 4477-4479 of 6105")
	)
	(layers
		(0 "F.Cu" signal "TOP")
		(4 "In1.Cu" signal "GND")
		(6 "In2.Cu" signal "IN1")
		(8 "In3.Cu" signal "GND1")
		(10 "In4.Cu" signal "IN2")
		(12 "In5.Cu" signal "GND2")
		(14 "In6.Cu" signal "IN3")
		(16 "In7.Cu" signal "GND3")
		(18 "In8.Cu" signal "VCC")
		(20 "In9.Cu" signal "VCC1")
		(22 "In10.Cu" signal "GND4")
		(24 "In11.Cu" signal "IN4")
		(26 "In12.Cu" signal "GND5")
		(28 "In13.Cu" signal "IN5")
		(30 "In14.Cu" signal "GND6")
		(32 "In15.Cu" signal "IN6")
		(34 "In16.Cu" signal "GND7")
		(2 "B.Cu" signal "BOTTOM")
		(9 "F.Adhes" user "F.Adhesive")
		(11 "B.Adhes" user "B.Adhesive")
		(13 "F.Paste" user "Package Geometry/Pastemask Top")
		(15 "B.Paste" user "Package Geometry/Pastemask Bottom")
		(5 "F.SilkS" user "Ref Des/Silkscreen Top")
		(7 "B.SilkS" user "Ref Des/Silkscreen Bottom")
		(1 "F.Mask" user "Board Geometry/Soldermask Top")
		(3 "B.Mask" user "Board Geometry/Soldermask Bottom")
		(17 "Dwgs.User" user "User.Drawings")
		(19 "Cmts.User" user "User.Comments")
		(21 "Eco1.User" user "User.Eco1")
		(23 "Eco2.User" user "User.Eco2")
		(25 "Edge.Cuts" user "Board Geometry/Outline")
		(27 "Margin" user)
		(31 "F.CrtYd" user "Package Geometry/Place Bound Top")
		(29 "B.CrtYd" user "Package Geometry/Place Bound Bottom")
		(35 "F.Fab" user "Ref Des/Assembly Top")
		(33 "B.Fab" user "Ref Des/Assembly Bottom")
	)
	(footprint ""
		(layer "B.Cu")
		(at 419.605968 -353.25939 -90)
		(property "Reference" "PC617_P0_1"
			(at 0 0 90)
			(layer "B.SilkS")
			(hide yes)
			(effects
				(font
					(size 1.27 1.27)
				)
				(justify mirror)
			)
		)
		(property "Value" ""
			(at 0 0 90)
			(layer "B.Fab")
			(effects
				(font
					(size 1.27 1.27)
				)
				(justify mirror)
			)
		)
		(duplicate_pad_numbers_are_jumpers no)
		(fp_line
			(start -1.524 0.762)
			(end 1.524 0.762)
			(stroke
				(width 0.1524)
				(type default)
			)
			(layer "B.SilkS")
		)
		(fp_line
			(start 1.524 0.762)
			(end 1.524 -0.762)
			(stroke
				(width 0.1524)
				(type default)
			)
			(layer "B.SilkS")
		)
		(fp_line
			(start -1.524 -0.762)
			(end -1.524 0.762)
			(stroke
				(width 0.1524)
				(type default)
			)
			(layer "B.SilkS")
		)
		(fp_line
			(start 1.524 -0.762)
			(end -1.524 -0.762)
			(stroke
				(width 0.1524)
				(type default)
			)
			(layer "B.SilkS")
		)
		(fp_line
			(start -1.1049 0.724916)
			(end -1.1049 -0.724916)
			(stroke
				(width 0.1)
				(type default)
			)
			(layer "B.Fab")
		)
		(fp_line
			(start 1.1049 0.724916)
			(end -1.1049 0.724916)
			(stroke
				(width 0.1)
				(type default)
			)
			(layer "B.Fab")
		)
		(fp_line
			(start -1.1049 -0.724916)
			(end 1.1049 -0.724916)
			(stroke
				(width 0.1)
				(type default)
			)
			(layer "B.Fab")
		)
		(fp_line
			(start 1.1049 -0.724916)
			(end 1.1049 0.724916)
			(stroke
				(width 0.1)
				(type default)
			)
			(layer "B.Fab")
		)
		(pad "1" smd rect
			(at 0.889 0 270)
			(size 1.016 1.27)
			(layers "B.Cu" "B.Mask" "B.Paste")
			(net "PVCCFA_EHV_FIVRA_CPU0")
		)
		(pad "2" smd rect
			(at -0.889 0 270)
			(size 1.016 1.27)
			(layers "B.Cu" "B.Mask" "B.Paste")
			(net "GND")
		)
	)
	(footprint ""
		(layer "B.Cu")
		(at 236.851698 -123.871482 90)
		(property "Reference" "C206"
			(at 0 0 90)
			(layer "B.SilkS")
			(hide yes)
			(effects
				(font
					(size 1.27 1.27)
				)
				(justify mirror)
			)
		)
		(property "Value" ""
			(at 0 0 90)
			(layer "B.Fab")
			(effects
				(font
					(size 1.27 1.27)
				)
				(justify mirror)
			)
		)
		(duplicate_pad_numbers_are_jumpers no)
		(fp_line
			(start 0.7874 -0.4064)
			(end -0.7874 -0.4064)
			(stroke
				(width 0.1524)
				(type default)
			)
			(layer "B.SilkS")
		)
		(fp_line
			(start -0.7874 -0.4064)
			(end -0.7874 0.4064)
			(stroke
				(width 0.1524)
				(type default)
			)
			(layer "B.SilkS")
		)
		(fp_line
			(start 0.7874 0.4064)
			(end 0.7874 -0.4064)
			(stroke
				(width 0.1524)
				(type default)
			)
			(layer "B.SilkS")
		)
		(fp_line
			(start -0.7874 0.4064)
			(end 0.7874 0.4064)
			(stroke
				(width 0.1524)
				(type default)
			)
			(layer "B.SilkS")
		)
		(fp_line
			(start 0.67945 -0.305054)
			(end 0.12065 -0.305054)
			(stroke
				(width 0.1)
				(type default)
			)
			(layer "B.Fab")
		)
		(fp_line
			(start 0.12065 -0.305054)
			(end 0.12065 -0.2794)
			(stroke
				(width 0.1)
				(type default)
			)
			(layer "B.Fab")
		)
		(fp_line
			(start -0.12065 -0.3048)
			(end -0.67945 -0.3048)
			(stroke
				(width 0.1)
				(type default)
			)
			(layer "B.Fab")
		)
		(fp_line
			(start -0.67945 -0.3048)
			(end -0.67945 0.3048)
			(stroke
				(width 0.1)
				(type default)
			)
			(layer "B.Fab")
		)
		(fp_line
			(start 0.12065 -0.2794)
			(end -0.12065 -0.2794)
			(stroke
				(width 0.1)
				(type default)
			)
			(layer "B.Fab")
		)
		(fp_line
			(start -0.12065 -0.2794)
			(end -0.12065 -0.3048)
			(stroke
				(width 0.1)
				(type default)
			)
			(layer "B.Fab")
		)
		(fp_line
			(start 0.12065 0.2794)
			(end 0.12065 0.3048)
			(stroke
				(width 0.1)
				(type default)
			)
			(layer "B.Fab")
		)
		(fp_line
			(start -0.120396 0.2794)
			(end 0.12065 0.2794)
			(stroke
				(width 0.1)
				(type default)
			)
			(layer "B.Fab")
		)
		(fp_line
			(start 0.67945 0.3048)
			(end 0.67945 -0.305054)
			(stroke
				(width 0.1)
				(type default)
			)
			(layer "B.Fab")
		)
		(fp_line
			(start 0.12065 0.3048)
			(end 0.67945 0.3048)
			(stroke
				(width 0.1)
				(type default)
			)
			(layer "B.Fab")
		)
		(fp_line
			(start -0.120396 0.3048)
			(end -0.120396 0.2794)
			(stroke
				(width 0.1)
				(type default)
			)
			(layer "B.Fab")
		)
		(fp_line
			(start -0.67945 0.3048)
			(end -0.120396 0.3048)
			(stroke
				(width 0.1)
				(type default)
			)
			(layer "B.Fab")
		)
		(pad "1" smd circle
			(at 0.40005 0 270)
			(size 0 0)
			(layers "B.Cu" "B.Mask" "B.Paste")
			(net "P3V3_DB2000_VDD")
		)
		(pad "2" smd circle
			(at -0.40005 0 270)
			(size 0 0)
			(layers "B.Cu" "B.Mask" "B.Paste")
			(net "GND")
		)
	)
	(footprint ""
		(layer "B.Cu")
		(at 449.5546 -10.594086 90)
		(property "Reference" "R423"
			(at 0 0 90)
			(layer "B.SilkS")
			(hide yes)
			(effects
				(font
					(size 1.27 1.27)
				)
				(justify mirror)
			)
		)
		(property "Value" ""
			(at 0 0 90)
			(layer "B.Fab")
			(effects
				(font
					(size 1.27 1.27)
				)
				(justify mirror)
			)
		)
		(duplicate_pad_numbers_are_jumpers no)
		(fp_line
			(start 0.7874 -0.4064)
			(end -0.7874 -0.4064)
			(stroke
				(width 0.1524)
				(type default)
			)
			(layer "B.SilkS")
		)
		(fp_line
			(start -0.7874 -0.4064)
			(end -0.7874 0.4064)
			(stroke
				(width 0.1524)
				(type default)
			)
			(layer "B.SilkS")
		)
		(fp_line
			(start 0.7874 0.4064)
			(end 0.7874 -0.4064)
			(stroke
				(width 0.1524)
				(type default)
			)
			(layer "B.SilkS")
		)
		(fp_line
			(start -0.7874 0.4064)
			(end 0.7874 0.4064)
			(stroke
				(width 0.1524)
				(type default)
			)
			(layer "B.SilkS")
		)
		(fp_line
			(start 0.67945 -0.305054)
			(end 0.12065 -0.305054)
			(stroke
				(width 0.1)
				(type default)
			)
			(layer "B.Fab")
		)
		(fp_line
			(start 0.12065 -0.305054)
			(end 0.12065 -0.2794)
			(stroke
				(width 0.1)
				(type default)
			)
			(layer "B.Fab")
		)
		(fp_line
			(start -0.12065 -0.3048)
			(end -0.67945 -0.3048)
			(stroke
				(width 0.1)
				(type default)
			)
			(layer "B.Fab")
		)
		(fp_line
			(start -0.67945 -0.3048)
			(end -0.67945 0.3048)
			(stroke
				(width 0.1)
				(type default)
			)
			(layer "B.Fab")
		)
		(fp_line
			(start 0.12065 -0.2794)
			(end -0.12065 -0.2794)
			(stroke
				(width 0.1)
				(type default)
			)
			(layer "B.Fab")
		)
		(fp_line
			(start -0.12065 -0.2794)
			(end -0.12065 -0.3048)
			(stroke
				(width 0.1)
				(type default)
			)
			(layer "B.Fab")
		)
		(fp_line
			(start 0.12065 0.2794)
			(end 0.12065 0.3048)
			(stroke
				(width 0.1)
				(type default)
			)
			(layer "B.Fab")
		)
		(fp_line
			(start -0.120396 0.2794)
			(end 0.12065 0.2794)
			(stroke
				(width 0.1)
				(type default)
			)
			(layer "B.Fab")
		)
		(fp_line
			(start 0.67945 0.3048)
			(end 0.67945 -0.305054)
			(stroke
				(width 0.1)
				(type default)
			)
			(layer "B.Fab")
		)
		(fp_line
			(start 0.12065 0.3048)
			(end 0.67945 0.3048)
			(stroke
				(width 0.1)
				(type default)
			)
			(layer "B.Fab")
		)
		(fp_line
			(start -0.120396 0.3048)
			(end -0.120396 0.2794)
			(stroke
				(width 0.1)
				(type default)
			)
			(layer "B.Fab")
		)
		(fp_line
			(start -0.67945 0.3048)
			(end -0.120396 0.3048)
			(stroke
				(width 0.1)
				(type default)
			)
			(layer "B.Fab")
		)
		(pad "1" smd circle
			(at 0.40005 0 270)
			(size 0 0)
			(layers "B.Cu" "B.Mask" "B.Paste")
			(net "SGPIO_OCP_SFF_CLK")
		)
		(pad "2" smd circle
			(at -0.40005 0 270)
			(size 0 0)
			(layers "B.Cu" "B.Mask" "B.Paste")
			(net "P3V3_OCP_SFF")
		)
	)
)
